(kicad_pcb
	(version 20260206)
	(generator "pcbnew")
	(generator_version "10.0")
	(general
		(thickness 1.6)
		(legacy_teardrops no)
	)
	(paper "A4")
	(title_block
		(title "Wiwynn_Tioga_Pass_MB.brd")
		(comment 1 "Tioga Pass / footprints 3907-3914 of 4770")
	)
	(layers
		(0 "F.Cu" signal "TOP")
		(4 "In1.Cu" signal "L2GND")
		(6 "In2.Cu" signal "L3")
		(8 "In3.Cu" signal "L4GND")
		(10 "In4.Cu" signal "L5")
		(12 "In5.Cu" signal "L6GND")
		(14 "In6.Cu" signal "L7VCC")
		(16 "In7.Cu" signal "L8VCC")
		(18 "In8.Cu" signal "L9GND")
		(20 "In9.Cu" signal "L10")
		(22 "In10.Cu" signal "L11GND")
		(24 "In11.Cu" signal "L12")
		(26 "In12.Cu" signal "L13GND")
		(2 "B.Cu" signal "BOTTOM")
		(9 "F.Adhes" user "F.Adhesive")
		(11 "B.Adhes" user "B.Adhesive")
		(13 "F.Paste" user "Package Geometry/Pastemask Top")
		(15 "B.Paste" user "Package Geometry/Pastemask Bottom")
		(5 "F.SilkS" user "Ref Des/Silkscreen Top")
		(7 "B.SilkS" user "Ref Des/Silkscreen Bottom")
		(1 "F.Mask" user "Board Geometry/Soldermask Top")
		(3 "B.Mask" user "Board Geometry/Soldermask Bottom")
		(17 "Dwgs.User" user "User.Drawings")
		(19 "Cmts.User" user "User.Comments")
		(21 "Eco1.User" user "User.Eco1")
		(23 "Eco2.User" user "User.Eco2")
		(25 "Edge.Cuts" user "Board Geometry/Outline")
		(27 "Margin" user)
		(31 "F.CrtYd" user "Package Geometry/Place Bound Top")
		(29 "B.CrtYd" user "Package Geometry/Place Bound Bottom")
		(35 "F.Fab" user "Ref Des/Assembly Top")
		(33 "B.Fab" user "Ref Des/Assembly Bottom")
	)
	(footprint ""
		(layer "B.Cu")
		(at 269.559532 -17.7546 90)
		(property "Reference" "C5T7"
			(at -1.848866 0.752348 90)
			(unlocked yes)
			(layer "B.SilkS")
			(effects
				(font
					(size 1.27 0.9652)
					(thickness 0.1524)
				)
				(justify mirror)
			)
		)
		(property "Value" ""
			(at 0 0 90)
			(layer "B.Fab")
			(effects
				(font
					(size 1.27 1.27)
				)
				(justify mirror)
			)
		)
		(duplicate_pad_numbers_are_jumpers no)
		(fp_rect
			(start 0.500126 1.598422)
			(end -0.500126 -0.201422)
			(stroke
				(width 0)
				(type default)
			)
			(fill no)
			(layer "B.CrtYd")
		)
		(fp_line
			(start 0.500126 -0.201422)
			(end -0.500126 -0.201422)
			(stroke
				(width 0.1)
				(type default)
			)
			(layer "B.Fab")
		)
		(fp_line
			(start -0.500126 -0.201422)
			(end -0.500126 1.598422)
			(stroke
				(width 0.1)
				(type default)
			)
			(layer "B.Fab")
		)
		(fp_line
			(start 0.500126 1.598422)
			(end 0.500126 -0.201422)
			(stroke
				(width 0.1)
				(type default)
			)
			(layer "B.Fab")
		)
		(fp_line
			(start -0.500126 1.598422)
			(end 0.500126 1.598422)
			(stroke
				(width 0.1)
				(type default)
			)
			(layer "B.Fab")
		)
		(pad "1" smd rect
			(at 0 0)
			(size 0.889 0.9906)
			(layers "B.Cu" "B.Mask" "B.Paste")
			(net "PVDDQ_ABC")
		)
		(pad "2" smd rect
			(at 0 1.397)
			(size 0.889 0.9906)
			(layers "B.Cu" "B.Mask" "B.Paste")
			(net "GND")
		)
		(zone
			(layer "B.Cu")
			(hatch none 0.5)
			(connect_pads
				(clearance 0)
			)
			(min_thickness 0.25)
			(keepout
				(tracks not_allowed)
				(vias allowed)
				(pads allowed)
				(copperpour not_allowed)
				(footprints allowed)
			)
			(placement
				(enabled no)
				(sheetname "")
			)
			(fill
				(thermal_gap 0.5)
				(thermal_bridge_width 0.5)
				(island_removal_mode 0)
			)
			(polygon
				(pts
					(xy 270.512032 -18.2499) (xy 270.004032 -18.2499) (xy 270.004032 -17.2593) (xy 270.512032 -17.2593)
				)
			)
		)
		(zone
			(layer "B.Cu")
			(hatch none 0.5)
			(connect_pads
				(clearance 0)
			)
			(min_thickness 0.25)
			(keepout
				(tracks allowed)
				(vias not_allowed)
				(pads allowed)
				(copperpour not_allowed)
				(footprints allowed)
			)
			(placement
				(enabled no)
				(sheetname "")
			)
			(fill
				(thermal_gap 0.5)
				(thermal_bridge_width 0.5)
				(island_removal_mode 0)
			)
			(polygon
				(pts
					(xy 270.512032 -18.2499) (xy 270.004032 -18.2499) (xy 270.004032 -17.2593) (xy 270.512032 -17.2593)
				)
			)
		)
	)
	(footprint ""
		(layer "B.Cu")
		(at 466.5472 -125.095 -90)
		(property "Reference" "R1W11"
			(at -1.47828 0.78994 0)
			(unlocked yes)
			(layer "B.SilkS")
			(effects
				(font
					(size 0.4064 0.254)
					(thickness 0.1524)
				)
				(justify mirror)
			)
		)
		(property "Value" ""
			(at 0 0 90)
			(layer "B.Fab")
			(effects
				(font
					(size 1.27 1.27)
				)
				(justify mirror)
			)
		)
		(duplicate_pad_numbers_are_jumpers no)
		(fp_poly
			(pts
				(xy 0.7239 -0.2159) (xy -0.7239 -0.2159) (xy -0.7239 1.9939) (xy 0.7239 1.9939)
			)
			(stroke
				(width 0)
				(type default)
			)
			(fill no)
			(layer "B.CrtYd")
		)
		(fp_line
			(start -0.7239 1.9939)
			(end -0.7239 -0.2159)
			(stroke
				(width 0.1)
				(type default)
			)
			(layer "B.Fab")
		)
		(fp_line
			(start 0.7239 1.9939)
			(end -0.7239 1.9939)
			(stroke
				(width 0.1)
				(type default)
			)
			(layer "B.Fab")
		)
		(fp_line
			(start -0.7239 -0.2159)
			(end 0.7239 -0.2159)
			(stroke
				(width 0.1)
				(type default)
			)
			(layer "B.Fab")
		)
		(fp_line
			(start 0.7239 -0.2159)
			(end 0.7239 1.9939)
			(stroke
				(width 0.1)
				(type default)
			)
			(layer "B.Fab")
		)
		(pad "1" smd rect
			(at 0 0 90)
			(size 1.27 1.016)
			(layers "B.Cu" "B.Mask" "B.Paste")
			(net "P5V")
		)
		(pad "2" smd rect
			(at 0 1.778 90)
			(size 1.27 1.016)
			(layers "B.Cu" "B.Mask" "B.Paste")
			(net "P5V_TPS2061")
		)
		(zone
			(layer "B.Cu")
			(hatch none 0.5)
			(connect_pads
				(clearance 0)
			)
			(min_thickness 0.25)
			(keepout
				(tracks not_allowed)
				(vias allowed)
				(pads allowed)
				(copperpour not_allowed)
				(footprints allowed)
			)
			(placement
				(enabled no)
				(sheetname "")
			)
			(fill
				(thermal_gap 0.5)
				(thermal_bridge_width 0.5)
				(island_removal_mode 0)
			)
			(polygon
				(pts
					(xy 466.0392 -125.73) (xy 465.2772 -125.73) (xy 465.2772 -125.6411) (xy 465.2772 -124.46) (xy 466.0392 -124.46)
				)
			)
		)
	)
	(footprint ""
		(layer "B.Cu")
		(at 93.05798 -140.16228 -90)
		(property "Reference" "C5G110"
			(at -1.14681 0.76708 0)
			(unlocked yes)
			(layer "B.SilkS")
			(effects
				(font
					(size 0.7874 0.5842)
					(thickness 0.1524)
				)
				(justify mirror)
			)
		)
		(property "Value" ""
			(at 0 0 90)
			(layer "B.Fab")
			(effects
				(font
					(size 1.27 1.27)
				)
				(justify mirror)
			)
		)
		(duplicate_pad_numbers_are_jumpers no)
		(fp_rect
			(start -0.4953 -0.2032)
			(end 0.4953 1.6002)
			(stroke
				(width 0)
				(type default)
			)
			(fill no)
			(layer "B.CrtYd")
		)
		(fp_line
			(start -0.4953 1.6002)
			(end 0.4953 1.6002)
			(stroke
				(width 0.1)
				(type default)
			)
			(layer "B.Fab")
		)
		(fp_line
			(start 0.4953 1.6002)
			(end 0.4953 -0.2032)
			(stroke
				(width 0.1)
				(type default)
			)
			(layer "B.Fab")
		)
		(fp_line
			(start -0.4953 -0.2032)
			(end -0.4953 1.6002)
			(stroke
				(width 0.1)
				(type default)
			)
			(layer "B.Fab")
		)
		(fp_line
			(start 0.4953 -0.2032)
			(end -0.4953 -0.2032)
			(stroke
				(width 0.1)
				(type default)
			)
			(layer "B.Fab")
		)
		(pad "1" smd rect
			(at 0 0 90)
			(size 0.762 0.889)
			(layers "B.Cu" "B.Mask" "B.Paste")
			(net "PVDDQ_KLM")
		)
		(pad "2" smd rect
			(at 0 1.397 90)
			(size 0.762 0.889)
			(layers "B.Cu" "B.Mask" "B.Paste")
			(net "GND")
		)
		(zone
			(layer "B.Cu")
			(hatch none 0.5)
			(connect_pads
				(clearance 0)
			)
			(min_thickness 0.25)
			(keepout
				(tracks not_allowed)
				(vias allowed)
				(pads allowed)
				(copperpour not_allowed)
				(footprints allowed)
			)
			(placement
				(enabled no)
				(sheetname "")
			)
			(fill
				(thermal_gap 0.5)
				(thermal_bridge_width 0.5)
				(island_removal_mode 0)
			)
			(polygon
				(pts
					(xy 92.61348 -140.54328) (xy 92.10548 -140.54328) (xy 92.10548 -139.78128) (xy 92.61348 -139.78128)
				)
			)
		)
	)
	(footprint ""
		(layer "B.Cu")
		(at 248.8565 -8.1534 -90)
		(property "Reference" "C5U8"
			(at -1.848866 0.752348 270)
			(unlocked yes)
			(layer "B.SilkS")
			(effects
				(font
					(size 1.27 0.9652)
					(thickness 0.1524)
				)
				(justify mirror)
			)
		)
		(property "Value" ""
			(at 0 0 90)
			(layer "B.Fab")
			(effects
				(font
					(size 1.27 1.27)
				)
				(justify mirror)
			)
		)
		(duplicate_pad_numbers_are_jumpers no)
		(fp_rect
			(start 0.500126 1.598422)
			(end -0.500126 -0.201422)
			(stroke
				(width 0)
				(type default)
			)
			(fill no)
			(layer "B.CrtYd")
		)
		(fp_line
			(start -0.500126 1.598422)
			(end 0.500126 1.598422)
			(stroke
				(width 0.1)
				(type default)
			)
			(layer "B.Fab")
		)
		(fp_line
			(start 0.500126 1.598422)
			(end 0.500126 -0.201422)
			(stroke
				(width 0.1)
				(type default)
			)
			(layer "B.Fab")
		)
		(fp_line
			(start -0.500126 -0.201422)
			(end -0.500126 1.598422)
			(stroke
				(width 0.1)
				(type default)
			)
			(layer "B.Fab")
		)
		(fp_line
			(start 0.500126 -0.201422)
			(end -0.500126 -0.201422)
			(stroke
				(width 0.1)
				(type default)
			)
			(layer "B.Fab")
		)
		(pad "1" smd rect
			(at 0 0 180)
			(size 0.889 0.9906)
			(layers "B.Cu" "B.Mask" "B.Paste")
			(net "PVDDQ_ABC")
		)
		(pad "2" smd rect
			(at 0 1.397 180)
			(size 0.889 0.9906)
			(layers "B.Cu" "B.Mask" "B.Paste")
			(net "GND")
		)
		(zone
			(layer "B.Cu")
			(hatch none 0.5)
			(connect_pads
				(clearance 0)
			)
			(min_thickness 0.25)
			(keepout
				(tracks allowed)
				(vias not_allowed)
				(pads allowed)
				(copperpour not_allowed)
				(footprints allowed)
			)
			(placement
				(enabled no)
				(sheetname "")
			)
			(fill
				(thermal_gap 0.5)
				(thermal_bridge_width 0.5)
				(island_removal_mode 0)
			)
			(polygon
				(pts
					(xy 247.904 -7.6581) (xy 248.412 -7.6581) (xy 248.412 -8.6487) (xy 247.904 -8.6487)
				)
			)
		)
		(zone
			(layer "B.Cu")
			(hatch none 0.5)
			(connect_pads
				(clearance 0)
			)
			(min_thickness 0.25)
			(keepout
				(tracks not_allowed)
				(vias allowed)
				(pads allowed)
				(copperpour not_allowed)
				(footprints allowed)
			)
			(placement
				(enabled no)
				(sheetname "")
			)
			(fill
				(thermal_gap 0.5)
				(thermal_bridge_width 0.5)
				(island_removal_mode 0)
			)
			(polygon
				(pts
					(xy 247.904 -7.6581) (xy 248.412 -7.6581) (xy 248.412 -8.6487) (xy 247.904 -8.6487)
				)
			)
		)
	)
	(footprint ""
		(layer "B.Cu")
		(at 359.84688 -77.923136 180)
		(property "Reference" "C3P39"
			(at 0 0 0)
			(layer "B.SilkS")
			(hide yes)
			(effects
				(font
					(size 1.27 1.27)
				)
				(justify mirror)
			)
		)
		(property "Value" ""
			(at 0 0 0)
			(layer "B.Fab")
			(effects
				(font
					(size 1.27 1.27)
				)
				(justify mirror)
			)
		)
		(duplicate_pad_numbers_are_jumpers no)
		(fp_poly
			(pts
				(xy -0.3048 -0.1016) (xy -0.3048 0.9906) (xy 0.3048 0.9906) (xy 0.3048 -0.1016)
			)
			(stroke
				(width 0)
				(type default)
			)
			(fill no)
			(layer "B.CrtYd")
		)
		(fp_line
			(start 0.3048 0.9906)
			(end -0.3048 0.9906)
			(stroke
				(width 0.1)
				(type default)
			)
			(layer "B.Fab")
		)
		(fp_line
			(start 0.3048 -0.1016)
			(end 0.3048 0.9906)
			(stroke
				(width 0.1)
				(type default)
			)
			(layer "B.Fab")
		)
		(fp_line
			(start -0.3048 0.9906)
			(end -0.3048 -0.1016)
			(stroke
				(width 0.1)
				(type default)
			)
			(layer "B.Fab")
		)
		(fp_line
			(start -0.3048 -0.1016)
			(end 0.3048 -0.1016)
			(stroke
				(width 0.1)
				(type default)
			)
			(layer "B.Fab")
		)
		(pad "1" smd rect
			(at 0 0)
			(size 0.508 0.508)
			(layers "B.Cu" "B.Mask" "B.Paste")
			(net "P3E_CPU0_PE1_SS_TXP<7>")
		)
		(pad "2" smd rect
			(at 0 0.889)
			(size 0.508 0.508)
			(layers "B.Cu" "B.Mask" "B.Paste")
			(net "P3E_CPU0_PE1_PCH_TXP<7>")
		)
		(zone
			(layer "B.Cu")
			(hatch none 0.5)
			(connect_pads
				(clearance 0)
			)
			(min_thickness 0.25)
			(keepout
				(tracks not_allowed)
				(vias allowed)
				(pads allowed)
				(copperpour not_allowed)
				(footprints allowed)
			)
			(placement
				(enabled no)
				(sheetname "")
			)
			(fill
				(thermal_gap 0.5)
				(thermal_bridge_width 0.5)
				(island_removal_mode 0)
			)
			(polygon
				(pts
					(xy 359.59288 -78.558136) (xy 360.10088 -78.558136) (xy 360.10088 -78.177136) (xy 359.59288 -78.177136)
				)
			)
		)
		(zone
			(layer "B.Cu")
			(hatch none 0.5)
			(connect_pads
				(clearance 0)
			)
			(min_thickness 0.25)
			(keepout
				(tracks allowed)
				(vias not_allowed)
				(pads allowed)
				(copperpour not_allowed)
				(footprints allowed)
			)
			(placement
				(enabled no)
				(sheetname "")
			)
			(fill
				(thermal_gap 0.5)
				(thermal_bridge_width 0.5)
				(island_removal_mode 0)
			)
			(polygon
				(pts
					(xy 359.59288 -78.177136) (xy 360.10088 -78.177136) (xy 360.10088 -78.558136) (xy 359.59288 -78.558136)
				)
			)
		)
	)
	(footprint ""
		(layer "B.Cu")
		(at 426.72 -142.0876)
		(property "Reference" "C2L40"
			(at 0 0 0)
			(layer "B.SilkS")
			(hide yes)
			(effects
				(font
					(size 1.27 1.27)
				)
				(justify mirror)
			)
		)
		(property "Value" ""
			(at 0 0 0)
			(layer "B.Fab")
			(effects
				(font
					(size 1.27 1.27)
				)
				(justify mirror)
			)
		)
		(duplicate_pad_numbers_are_jumpers no)
		(fp_poly
			(pts
				(xy -0.3048 -0.1016) (xy -0.3048 0.9906) (xy 0.3048 0.9906) (xy 0.3048 -0.1016)
			)
			(stroke
				(width 0)
				(type default)
			)
			(fill no)
			(layer "B.CrtYd")
		)
		(fp_line
			(start -0.3048 -0.1016)
			(end 0.3048 -0.1016)
			(stroke
				(width 0.1)
				(type default)
			)
			(layer "B.Fab")
		)
		(fp_line
			(start -0.3048 0.9906)
			(end -0.3048 -0.1016)
			(stroke
				(width 0.1)
				(type default)
			)
			(layer "B.Fab")
		)
		(fp_line
			(start 0.3048 -0.1016)
			(end 0.3048 0.9906)
			(stroke
				(width 0.1)
				(type default)
			)
			(layer "B.Fab")
		)
		(fp_line
			(start 0.3048 0.9906)
			(end -0.3048 0.9906)
			(stroke
				(width 0.1)
				(type default)
			)
			(layer "B.Fab")
		)
		(pad "1" smd rect
			(at 0 0 180)
			(size 0.508 0.508)
			(layers "B.Cu" "B.Mask" "B.Paste")
			(net "SATA6G_P0_TX_C_DN")
		)
		(pad "2" smd rect
			(at 0 0.889 180)
			(size 0.508 0.508)
			(layers "B.Cu" "B.Mask" "B.Paste")
			(net "SATA6G_PCH_PCIE_UP_SATA_TXN<0>")
		)
		(zone
			(layer "B.Cu")
			(hatch none 0.5)
			(connect_pads
				(clearance 0)
			)
			(min_thickness 0.25)
			(keepout
				(tracks allowed)
				(vias not_allowed)
				(pads allowed)
				(copperpour not_allowed)
				(footprints allowed)
			)
			(placement
				(enabled no)
				(sheetname "")
			)
			(fill
				(thermal_gap 0.5)
				(thermal_bridge_width 0.5)
				(island_removal_mode 0)
			)
			(polygon
				(pts
					(xy 426.974 -141.8336) (xy 426.466 -141.8336) (xy 426.466 -141.4526) (xy 426.974 -141.4526)
				)
			)
		)
		(zone
			(layer "B.Cu")
			(hatch none 0.5)
			(connect_pads
				(clearance 0)
			)
			(min_thickness 0.25)
			(keepout
				(tracks not_allowed)
				(vias allowed)
				(pads allowed)
				(copperpour not_allowed)
				(footprints allowed)
			)
			(placement
				(enabled no)
				(sheetname "")
			)
			(fill
				(thermal_gap 0.5)
				(thermal_bridge_width 0.5)
				(island_removal_mode 0)
			)
			(polygon
				(pts
					(xy 426.974 -141.4526) (xy 426.466 -141.4526) (xy 426.466 -141.8336) (xy 426.974 -141.8336)
				)
			)
		)
	)
	(footprint ""
		(layer "B.Cu")
		(at 348.615 -144.565624 -90)
		(property "Reference" "C3L17"
			(at 0 0 90)
			(layer "B.SilkS")
			(hide yes)
			(effects
				(font
					(size 1.27 1.27)
				)
				(justify mirror)
			)
		)
		(property "Value" ""
			(at 0 0 90)
			(layer "B.Fab")
			(effects
				(font
					(size 1.27 1.27)
				)
				(justify mirror)
			)
		)
		(duplicate_pad_numbers_are_jumpers no)
		(fp_poly
			(pts
				(xy 0.7239 -0.2159) (xy -0.7239 -0.2159) (xy -0.7239 1.9939) (xy 0.7239 1.9939)
			)
			(stroke
				(width 0)
				(type default)
			)
			(fill no)
			(layer "B.CrtYd")
		)
		(fp_line
			(start -0.7239 1.9939)
			(end -0.7239 -0.2159)
			(stroke
				(width 0.1)
				(type default)
			)
			(layer "B.Fab")
		)
		(fp_line
			(start 0.7239 1.9939)
			(end -0.7239 1.9939)
			(stroke
				(width 0.1)
				(type default)
			)
			(layer "B.Fab")
		)
		(fp_line
			(start -0.7239 -0.2159)
			(end 0.7239 -0.2159)
			(stroke
				(width 0.1)
				(type default)
			)
			(layer "B.Fab")
		)
		(fp_line
			(start 0.7239 -0.2159)
			(end 0.7239 1.9939)
			(stroke
				(width 0.1)
				(type default)
			)
			(layer "B.Fab")
		)
		(pad "1" smd rect
			(at 0 0 90)
			(size 1.27 1.016)
			(layers "B.Cu" "B.Mask" "B.Paste")
			(net "VR_FET_SW_P12V_STBY_PVDDQ_DEF")
		)
		(pad "2" smd rect
			(at 0 1.778 90)
			(size 1.27 1.016)
			(layers "B.Cu" "B.Mask" "B.Paste")
			(net "GND")
		)
		(zone
			(layer "B.Cu")
			(hatch none 0.5)
			(connect_pads
				(clearance 0)
			)
			(min_thickness 0.25)
			(keepout
				(tracks not_allowed)
				(vias allowed)
				(pads allowed)
				(copperpour not_allowed)
				(footprints allowed)
			)
			(placement
				(enabled no)
				(sheetname "")
			)
			(fill
				(thermal_gap 0.5)
				(thermal_bridge_width 0.5)
				(island_removal_mode 0)
			)
			(polygon
				(pts
					(xy 348.107 -143.930624) (xy 348.107 -145.200624) (xy 347.345 -145.200624) (xy 347.345 -143.930624)
				)
			)
		)
	)
	(footprint ""
		(layer "B.Cu")
		(at 434.365654 -141.002512 180)
		(property "Reference" "C2L50"
			(at 0 0 0)
			(layer "B.SilkS")
			(hide yes)
			(effects
				(font
					(size 1.27 1.27)
				)
				(justify mirror)
			)
		)
		(property "Value" ""
			(at 0 0 0)
			(layer "B.Fab")
			(effects
				(font
					(size 1.27 1.27)
				)
				(justify mirror)
			)
		)
		(duplicate_pad_numbers_are_jumpers no)
		(fp_poly
			(pts
				(xy -0.3048 -0.1016) (xy -0.3048 0.9906) (xy 0.3048 0.9906) (xy 0.3048 -0.1016)
			)
			(stroke
				(width 0)
				(type default)
			)
			(fill no)
			(layer "B.CrtYd")
		)
		(fp_line
			(start 0.3048 0.9906)
			(end -0.3048 0.9906)
			(stroke
				(width 0.1)
				(type default)
			)
			(layer "B.Fab")
		)
		(fp_line
			(start 0.3048 -0.1016)
			(end 0.3048 0.9906)
			(stroke
				(width 0.1)
				(type default)
			)
			(layer "B.Fab")
		)
		(fp_line
			(start -0.3048 0.9906)
			(end -0.3048 -0.1016)
			(stroke
				(width 0.1)
				(type default)
			)
			(layer "B.Fab")
		)
		(fp_line
			(start -0.3048 -0.1016)
			(end 0.3048 -0.1016)
			(stroke
				(width 0.1)
				(type default)
			)
			(layer "B.Fab")
		)
		(pad "1" smd rect
			(at 0 0)
			(size 0.508 0.508)
			(layers "B.Cu" "B.Mask" "B.Paste")
			(net "SATA6G_S1_RX_C_DN")
		)
		(pad "2" smd rect
			(at 0 0.889)
			(size 0.508 0.508)
			(layers "B.Cu" "B.Mask" "B.Paste")
			(net "SATA6G_S1_RX_DN")
		)
		(zone
			(layer "B.Cu")
			(hatch none 0.5)
			(connect_pads
				(clearance 0)
			)
			(min_thickness 0.25)
			(keepout
				(tracks not_allowed)
				(vias allowed)
				(pads allowed)
				(copperpour not_allowed)
				(footprints allowed)
			)
			(placement
				(enabled no)
				(sheetname "")
			)
			(fill
				(thermal_gap 0.5)
				(thermal_bridge_width 0.5)
				(island_removal_mode 0)
			)
			(polygon
				(pts
					(xy 434.111654 -141.637512) (xy 434.619654 -141.637512) (xy 434.619654 -141.256512) (xy 434.111654 -141.256512)
				)
			)
		)
		(zone
			(layer "B.Cu")
			(hatch none 0.5)
			(connect_pads
				(clearance 0)
			)
			(min_thickness 0.25)
			(keepout
				(tracks allowed)
				(vias not_allowed)
				(pads allowed)
				(copperpour not_allowed)
				(footprints allowed)
			)
			(placement
				(enabled no)
				(sheetname "")
			)
			(fill
				(thermal_gap 0.5)
				(thermal_bridge_width 0.5)
				(island_removal_mode 0)
			)
			(polygon
				(pts
					(xy 434.111654 -141.256512) (xy 434.619654 -141.256512) (xy 434.619654 -141.637512) (xy 434.111654 -141.637512)
				)
			)
		)
	)
)
